(kicad_pcb
	(version 20260206)
	(generator "pcbnew")
	(generator_version "10.0")
	(general
		(thickness 1.6)
		(legacy_teardrops no)
	)
	(paper "A4")
	(title_block
		(title "03242023_DA0F0TMBIJ0_F0T_Motherboard_J_brd_V01_OCP.brd")
		(comment 1 "Grand Teton / footprints 5706-5712 of 6105")
	)
	(layers
		(0 "F.Cu" signal "TOP")
		(4 "In1.Cu" signal "GND")
		(6 "In2.Cu" signal "IN1")
		(8 "In3.Cu" signal "GND1")
		(10 "In4.Cu" signal "IN2")
		(12 "In5.Cu" signal "GND2")
		(14 "In6.Cu" signal "IN3")
		(16 "In7.Cu" signal "GND3")
		(18 "In8.Cu" signal "VCC")
		(20 "In9.Cu" signal "VCC1")
		(22 "In10.Cu" signal "GND4")
		(24 "In11.Cu" signal "IN4")
		(26 "In12.Cu" signal "GND5")
		(28 "In13.Cu" signal "IN5")
		(30 "In14.Cu" signal "GND6")
		(32 "In15.Cu" signal "IN6")
		(34 "In16.Cu" signal "GND7")
		(2 "B.Cu" signal "BOTTOM")
		(9 "F.Adhes" user "F.Adhesive")
		(11 "B.Adhes" user "B.Adhesive")
		(13 "F.Paste" user "Package Geometry/Pastemask Top")
		(15 "B.Paste" user "Package Geometry/Pastemask Bottom")
		(5 "F.SilkS" user "Ref Des/Silkscreen Top")
		(7 "B.SilkS" user "Ref Des/Silkscreen Bottom")
		(1 "F.Mask" user "Board Geometry/Soldermask Top")
		(3 "B.Mask" user "Board Geometry/Soldermask Bottom")
		(17 "Dwgs.User" user "User.Drawings")
		(19 "Cmts.User" user "User.Comments")
		(21 "Eco1.User" user "User.Eco1")
		(23 "Eco2.User" user "User.Eco2")
		(25 "Edge.Cuts" user "Board Geometry/Outline")
		(27 "Margin" user)
		(31 "F.CrtYd" user "Package Geometry/Place Bound Top")
		(29 "B.CrtYd" user "Package Geometry/Place Bound Bottom")
		(35 "F.Fab" user "Ref Des/Assembly Top")
		(33 "B.Fab" user "Ref Des/Assembly Bottom")
	)
	(footprint ""
		(layer "B.Cu")
		(at 353.610418 -294.009826)
		(property "Reference" "C369"
			(at 0 0 0)
			(layer "B.SilkS")
			(hide yes)
			(effects
				(font
					(size 1.27 1.27)
				)
				(justify mirror)
			)
		)
		(property "Value" ""
			(at 0 0 0)
			(layer "B.Fab")
			(effects
				(font
					(size 1.27 1.27)
				)
				(justify mirror)
			)
		)
		(duplicate_pad_numbers_are_jumpers no)
		(fp_line
			(start -1.524 -0.762)
			(end -1.524 0.762)
			(stroke
				(width 0.1524)
				(type default)
			)
			(layer "B.SilkS")
		)
		(fp_line
			(start -1.524 0.762)
			(end 1.524 0.762)
			(stroke
				(width 0.1524)
				(type default)
			)
			(layer "B.SilkS")
		)
		(fp_line
			(start 1.524 -0.762)
			(end -1.524 -0.762)
			(stroke
				(width 0.1524)
				(type default)
			)
			(layer "B.SilkS")
		)
		(fp_line
			(start 1.524 0.762)
			(end 1.524 -0.762)
			(stroke
				(width 0.1524)
				(type default)
			)
			(layer "B.SilkS")
		)
		(fp_line
			(start -1.1049 -0.724916)
			(end 1.1049 -0.724916)
			(stroke
				(width 0.1)
				(type default)
			)
			(layer "B.Fab")
		)
		(fp_line
			(start -1.1049 0.724916)
			(end -1.1049 -0.724916)
			(stroke
				(width 0.1)
				(type default)
			)
			(layer "B.Fab")
		)
		(fp_line
			(start 1.1049 -0.724916)
			(end 1.1049 0.724916)
			(stroke
				(width 0.1)
				(type default)
			)
			(layer "B.Fab")
		)
		(fp_line
			(start 1.1049 0.724916)
			(end -1.1049 0.724916)
			(stroke
				(width 0.1)
				(type default)
			)
			(layer "B.Fab")
		)
		(pad "1" smd rect
			(at 0.889 0)
			(size 1.016 1.27)
			(layers "B.Cu" "B.Mask" "B.Paste")
			(net "PVCCIN_CPU0")
		)
		(pad "2" smd rect
			(at -0.889 0)
			(size 1.016 1.27)
			(layers "B.Cu" "B.Mask" "B.Paste")
			(net "GND")
		)
	)
	(footprint ""
		(layer "B.Cu")
		(at 236.925612 -250.480322)
		(property "Reference" "C1889"
			(at 0 0 0)
			(layer "B.SilkS")
			(hide yes)
			(effects
				(font
					(size 1.27 1.27)
				)
				(justify mirror)
			)
		)
		(property "Value" ""
			(at 0 0 0)
			(layer "B.Fab")
			(effects
				(font
					(size 1.27 1.27)
				)
				(justify mirror)
			)
		)
		(duplicate_pad_numbers_are_jumpers no)
		(fp_line
			(start -0.7874 -0.4064)
			(end -0.7874 0.4064)
			(stroke
				(width 0.1524)
				(type default)
			)
			(layer "B.SilkS")
		)
		(fp_line
			(start -0.7874 0.4064)
			(end 0.7874 0.4064)
			(stroke
				(width 0.1524)
				(type default)
			)
			(layer "B.SilkS")
		)
		(fp_line
			(start 0.7874 -0.4064)
			(end -0.7874 -0.4064)
			(stroke
				(width 0.1524)
				(type default)
			)
			(layer "B.SilkS")
		)
		(fp_line
			(start 0.7874 0.4064)
			(end 0.7874 -0.4064)
			(stroke
				(width 0.1524)
				(type default)
			)
			(layer "B.SilkS")
		)
		(fp_line
			(start -0.67945 -0.3048)
			(end -0.67945 0.3048)
			(stroke
				(width 0.1)
				(type default)
			)
			(layer "B.Fab")
		)
		(fp_line
			(start -0.67945 0.3048)
			(end -0.120396 0.3048)
			(stroke
				(width 0.1)
				(type default)
			)
			(layer "B.Fab")
		)
		(fp_line
			(start -0.12065 -0.3048)
			(end -0.67945 -0.3048)
			(stroke
				(width 0.1)
				(type default)
			)
			(layer "B.Fab")
		)
		(fp_line
			(start -0.12065 -0.2794)
			(end -0.12065 -0.3048)
			(stroke
				(width 0.1)
				(type default)
			)
			(layer "B.Fab")
		)
		(fp_line
			(start -0.120396 0.2794)
			(end 0.12065 0.2794)
			(stroke
				(width 0.1)
				(type default)
			)
			(layer "B.Fab")
		)
		(fp_line
			(start -0.120396 0.3048)
			(end -0.120396 0.2794)
			(stroke
				(width 0.1)
				(type default)
			)
			(layer "B.Fab")
		)
		(fp_line
			(start 0.12065 -0.305054)
			(end 0.12065 -0.2794)
			(stroke
				(width 0.1)
				(type default)
			)
			(layer "B.Fab")
		)
		(fp_line
			(start 0.12065 -0.2794)
			(end -0.12065 -0.2794)
			(stroke
				(width 0.1)
				(type default)
			)
			(layer "B.Fab")
		)
		(fp_line
			(start 0.12065 0.2794)
			(end 0.12065 0.3048)
			(stroke
				(width 0.1)
				(type default)
			)
			(layer "B.Fab")
		)
		(fp_line
			(start 0.12065 0.3048)
			(end 0.67945 0.3048)
			(stroke
				(width 0.1)
				(type default)
			)
			(layer "B.Fab")
		)
		(fp_line
			(start 0.67945 -0.305054)
			(end 0.12065 -0.305054)
			(stroke
				(width 0.1)
				(type default)
			)
			(layer "B.Fab")
		)
		(fp_line
			(start 0.67945 0.3048)
			(end 0.67945 -0.305054)
			(stroke
				(width 0.1)
				(type default)
			)
			(layer "B.Fab")
		)
		(pad "1" smd circle
			(at 0.40005 0 180)
			(size 0 0)
			(layers "B.Cu" "B.Mask" "B.Paste")
			(net "VFG3P3_CLK_GEN")
		)
		(pad "2" smd circle
			(at -0.40005 0 180)
			(size 0 0)
			(layers "B.Cu" "B.Mask" "B.Paste")
			(net "GND")
		)
	)
	(footprint ""
		(layer "B.Cu")
		(at 358.80675 -359.47985)
		(property "Reference" "PR158"
			(at 0 0 0)
			(layer "B.SilkS")
			(hide yes)
			(effects
				(font
					(size 1.27 1.27)
				)
				(justify mirror)
			)
		)
		(property "Value" ""
			(at 0 0 0)
			(layer "B.Fab")
			(effects
				(font
					(size 1.27 1.27)
				)
				(justify mirror)
			)
		)
		(duplicate_pad_numbers_are_jumpers no)
		(fp_line
			(start -0.7874 -0.4064)
			(end -0.7874 0.4064)
			(stroke
				(width 0.1524)
				(type default)
			)
			(layer "B.SilkS")
		)
		(fp_line
			(start -0.7874 0.4064)
			(end 0.7874 0.4064)
			(stroke
				(width 0.1524)
				(type default)
			)
			(layer "B.SilkS")
		)
		(fp_line
			(start 0.7874 -0.4064)
			(end -0.7874 -0.4064)
			(stroke
				(width 0.1524)
				(type default)
			)
			(layer "B.SilkS")
		)
		(fp_line
			(start 0.7874 0.4064)
			(end 0.7874 -0.4064)
			(stroke
				(width 0.1524)
				(type default)
			)
			(layer "B.SilkS")
		)
		(fp_line
			(start -0.67945 -0.3048)
			(end -0.67945 0.3048)
			(stroke
				(width 0.1)
				(type default)
			)
			(layer "B.Fab")
		)
		(fp_line
			(start -0.67945 0.3048)
			(end -0.120396 0.3048)
			(stroke
				(width 0.1)
				(type default)
			)
			(layer "B.Fab")
		)
		(fp_line
			(start -0.12065 -0.3048)
			(end -0.67945 -0.3048)
			(stroke
				(width 0.1)
				(type default)
			)
			(layer "B.Fab")
		)
		(fp_line
			(start -0.12065 -0.2794)
			(end -0.12065 -0.3048)
			(stroke
				(width 0.1)
				(type default)
			)
			(layer "B.Fab")
		)
		(fp_line
			(start -0.120396 0.2794)
			(end 0.12065 0.2794)
			(stroke
				(width 0.1)
				(type default)
			)
			(layer "B.Fab")
		)
		(fp_line
			(start -0.120396 0.3048)
			(end -0.120396 0.2794)
			(stroke
				(width 0.1)
				(type default)
			)
			(layer "B.Fab")
		)
		(fp_line
			(start 0.12065 -0.305054)
			(end 0.12065 -0.2794)
			(stroke
				(width 0.1)
				(type default)
			)
			(layer "B.Fab")
		)
		(fp_line
			(start 0.12065 -0.2794)
			(end -0.12065 -0.2794)
			(stroke
				(width 0.1)
				(type default)
			)
			(layer "B.Fab")
		)
		(fp_line
			(start 0.12065 0.2794)
			(end 0.12065 0.3048)
			(stroke
				(width 0.1)
				(type default)
			)
			(layer "B.Fab")
		)
		(fp_line
			(start 0.12065 0.3048)
			(end 0.67945 0.3048)
			(stroke
				(width 0.1)
				(type default)
			)
			(layer "B.Fab")
		)
		(fp_line
			(start 0.67945 -0.305054)
			(end 0.12065 -0.305054)
			(stroke
				(width 0.1)
				(type default)
			)
			(layer "B.Fab")
		)
		(fp_line
			(start 0.67945 0.3048)
			(end 0.67945 -0.305054)
			(stroke
				(width 0.1)
				(type default)
			)
			(layer "B.Fab")
		)
		(pad "1" smd circle
			(at 0.40005 0 180)
			(size 0 0)
			(layers "B.Cu" "B.Mask" "B.Paste")
			(net "PVCCIN_CPU0_CSPIN")
		)
		(pad "2" smd circle
			(at -0.40005 0 180)
			(size 0 0)
			(layers "B.Cu" "B.Mask" "B.Paste")
			(net "GND")
		)
	)
	(footprint ""
		(layer "B.Cu")
		(at 433.461414 -321.549776 -90)
		(property "Reference" "C34"
			(at 0 0 90)
			(layer "B.SilkS")
			(hide yes)
			(effects
				(font
					(size 1.27 1.27)
				)
				(justify mirror)
			)
		)
		(property "Value" ""
			(at 0 0 90)
			(layer "B.Fab")
			(effects
				(font
					(size 1.27 1.27)
				)
				(justify mirror)
			)
		)
		(duplicate_pad_numbers_are_jumpers no)
		(fp_line
			(start -1.524 0.762)
			(end 1.524 0.762)
			(stroke
				(width 0.1524)
				(type default)
			)
			(layer "B.SilkS")
		)
		(fp_line
			(start 1.524 0.762)
			(end 1.524 -0.762)
			(stroke
				(width 0.1524)
				(type default)
			)
			(layer "B.SilkS")
		)
		(fp_line
			(start -1.524 -0.762)
			(end -1.524 0.762)
			(stroke
				(width 0.1524)
				(type default)
			)
			(layer "B.SilkS")
		)
		(fp_line
			(start 1.524 -0.762)
			(end -1.524 -0.762)
			(stroke
				(width 0.1524)
				(type default)
			)
			(layer "B.SilkS")
		)
		(fp_line
			(start -1.1049 0.724916)
			(end -1.1049 -0.724916)
			(stroke
				(width 0.1)
				(type default)
			)
			(layer "B.Fab")
		)
		(fp_line
			(start 1.1049 0.724916)
			(end -1.1049 0.724916)
			(stroke
				(width 0.1)
				(type default)
			)
			(layer "B.Fab")
		)
		(fp_line
			(start -1.1049 -0.724916)
			(end 1.1049 -0.724916)
			(stroke
				(width 0.1)
				(type default)
			)
			(layer "B.Fab")
		)
		(fp_line
			(start 1.1049 -0.724916)
			(end 1.1049 0.724916)
			(stroke
				(width 0.1)
				(type default)
			)
			(layer "B.Fab")
		)
		(pad "1" smd rect
			(at 0.889 0 270)
			(size 1.016 1.27)
			(layers "B.Cu" "B.Mask" "B.Paste")
			(net "P12V_S3_AUX_CPU0_NVDIMM")
		)
		(pad "2" smd rect
			(at -0.889 0 270)
			(size 1.016 1.27)
			(layers "B.Cu" "B.Mask" "B.Paste")
			(net "GND")
		)
	)
	(footprint ""
		(layer "B.Cu")
		(at 369.055142 -357.667306 180)
		(property "Reference" "PC1421"
			(at 0 0 0)
			(layer "B.SilkS")
			(hide yes)
			(effects
				(font
					(size 1.27 1.27)
				)
				(justify mirror)
			)
		)
		(property "Value" ""
			(at 0 0 0)
			(layer "B.Fab")
			(effects
				(font
					(size 1.27 1.27)
				)
				(justify mirror)
			)
		)
		(duplicate_pad_numbers_are_jumpers no)
		(fp_line
			(start 0.7874 0.4064)
			(end 0.7874 -0.4064)
			(stroke
				(width 0.1524)
				(type default)
			)
			(layer "B.SilkS")
		)
		(fp_line
			(start 0.7874 -0.4064)
			(end -0.7874 -0.4064)
			(stroke
				(width 0.1524)
				(type default)
			)
			(layer "B.SilkS")
		)
		(fp_line
			(start -0.7874 0.4064)
			(end 0.7874 0.4064)
			(stroke
				(width 0.1524)
				(type default)
			)
			(layer "B.SilkS")
		)
		(fp_line
			(start -0.7874 -0.4064)
			(end -0.7874 0.4064)
			(stroke
				(width 0.1524)
				(type default)
			)
			(layer "B.SilkS")
		)
		(fp_line
			(start 0.67945 0.3048)
			(end 0.67945 -0.305054)
			(stroke
				(width 0.1)
				(type default)
			)
			(layer "B.Fab")
		)
		(fp_line
			(start 0.67945 -0.305054)
			(end 0.12065 -0.305054)
			(stroke
				(width 0.1)
				(type default)
			)
			(layer "B.Fab")
		)
		(fp_line
			(start 0.12065 0.3048)
			(end 0.67945 0.3048)
			(stroke
				(width 0.1)
				(type default)
			)
			(layer "B.Fab")
		)
		(fp_line
			(start 0.12065 0.2794)
			(end 0.12065 0.3048)
			(stroke
				(width 0.1)
				(type default)
			)
			(layer "B.Fab")
		)
		(fp_line
			(start 0.12065 -0.2794)
			(end -0.12065 -0.2794)
			(stroke
				(width 0.1)
				(type default)
			)
			(layer "B.Fab")
		)
		(fp_line
			(start 0.12065 -0.305054)
			(end 0.12065 -0.2794)
			(stroke
				(width 0.1)
				(type default)
			)
			(layer "B.Fab")
		)
		(fp_line
			(start -0.120396 0.3048)
			(end -0.120396 0.2794)
			(stroke
				(width 0.1)
				(type default)
			)
			(layer "B.Fab")
		)
		(fp_line
			(start -0.120396 0.2794)
			(end 0.12065 0.2794)
			(stroke
				(width 0.1)
				(type default)
			)
			(layer "B.Fab")
		)
		(fp_line
			(start -0.12065 -0.2794)
			(end -0.12065 -0.3048)
			(stroke
				(width 0.1)
				(type default)
			)
			(layer "B.Fab")
		)
		(fp_line
			(start -0.12065 -0.3048)
			(end -0.67945 -0.3048)
			(stroke
				(width 0.1)
				(type default)
			)
			(layer "B.Fab")
		)
		(fp_line
			(start -0.67945 0.3048)
			(end -0.120396 0.3048)
			(stroke
				(width 0.1)
				(type default)
			)
			(layer "B.Fab")
		)
		(fp_line
			(start -0.67945 -0.3048)
			(end -0.67945 0.3048)
			(stroke
				(width 0.1)
				(type default)
			)
			(layer "B.Fab")
		)
		(pad "1" smd circle
			(at 0.40005 0)
			(size 0 0)
			(layers "B.Cu" "B.Mask" "B.Paste")
			(net "SH_PVPP_HBM_CPU0_P")
		)
		(pad "2" smd circle
			(at -0.40005 0)
			(size 0 0)
			(layers "B.Cu" "B.Mask" "B.Paste")
			(net "SH_PVPP_HBM_CPU0_N")
		)
	)
	(footprint ""
		(layer "B.Cu")
		(at 53.912516 -145.445226)
		(property "Reference" "PR255"
			(at 0 0 0)
			(layer "B.SilkS")
			(hide yes)
			(effects
				(font
					(size 1.27 1.27)
				)
				(justify mirror)
			)
		)
		(property "Value" ""
			(at 0 0 0)
			(layer "B.Fab")
			(effects
				(font
					(size 1.27 1.27)
				)
				(justify mirror)
			)
		)
		(duplicate_pad_numbers_are_jumpers no)
		(fp_line
			(start -0.7874 -0.4064)
			(end -0.7874 0.4064)
			(stroke
				(width 0.1524)
				(type default)
			)
			(layer "B.SilkS")
		)
		(fp_line
			(start -0.7874 0.4064)
			(end 0.7874 0.4064)
			(stroke
				(width 0.1524)
				(type default)
			)
			(layer "B.SilkS")
		)
		(fp_line
			(start 0.7874 -0.4064)
			(end -0.7874 -0.4064)
			(stroke
				(width 0.1524)
				(type default)
			)
			(layer "B.SilkS")
		)
		(fp_line
			(start 0.7874 0.4064)
			(end 0.7874 -0.4064)
			(stroke
				(width 0.1524)
				(type default)
			)
			(layer "B.SilkS")
		)
		(fp_line
			(start -0.67945 -0.3048)
			(end -0.67945 0.3048)
			(stroke
				(width 0.1)
				(type default)
			)
			(layer "B.Fab")
		)
		(fp_line
			(start -0.67945 0.3048)
			(end -0.120396 0.3048)
			(stroke
				(width 0.1)
				(type default)
			)
			(layer "B.Fab")
		)
		(fp_line
			(start -0.12065 -0.3048)
			(end -0.67945 -0.3048)
			(stroke
				(width 0.1)
				(type default)
			)
			(layer "B.Fab")
		)
		(fp_line
			(start -0.12065 -0.2794)
			(end -0.12065 -0.3048)
			(stroke
				(width 0.1)
				(type default)
			)
			(layer "B.Fab")
		)
		(fp_line
			(start -0.120396 0.2794)
			(end 0.12065 0.2794)
			(stroke
				(width 0.1)
				(type default)
			)
			(layer "B.Fab")
		)
		(fp_line
			(start -0.120396 0.3048)
			(end -0.120396 0.2794)
			(stroke
				(width 0.1)
				(type default)
			)
			(layer "B.Fab")
		)
		(fp_line
			(start 0.12065 -0.305054)
			(end 0.12065 -0.2794)
			(stroke
				(width 0.1)
				(type default)
			)
			(layer "B.Fab")
		)
		(fp_line
			(start 0.12065 -0.2794)
			(end -0.12065 -0.2794)
			(stroke
				(width 0.1)
				(type default)
			)
			(layer "B.Fab")
		)
		(fp_line
			(start 0.12065 0.2794)
			(end 0.12065 0.3048)
			(stroke
				(width 0.1)
				(type default)
			)
			(layer "B.Fab")
		)
		(fp_line
			(start 0.12065 0.3048)
			(end 0.67945 0.3048)
			(stroke
				(width 0.1)
				(type default)
			)
			(layer "B.Fab")
		)
		(fp_line
			(start 0.67945 -0.305054)
			(end 0.12065 -0.305054)
			(stroke
				(width 0.1)
				(type default)
			)
			(layer "B.Fab")
		)
		(fp_line
			(start 0.67945 0.3048)
			(end 0.67945 -0.305054)
			(stroke
				(width 0.1)
				(type default)
			)
			(layer "B.Fab")
		)
		(pad "1" smd circle
			(at 0.40005 0 180)
			(size 0 0)
			(layers "B.Cu" "B.Mask" "B.Paste")
			(net "PVCCFA_EHV_CPU1_PVCC")
		)
		(pad "2" smd circle
			(at -0.40005 0 180)
			(size 0 0)
			(layers "B.Cu" "B.Mask" "B.Paste")
			(net "PVCCINFAON_CPU1_VDD2")
		)
	)
	(footprint ""
		(layer "B.Cu")
		(at 310.957214 -258.379976 -90)
		(property "Reference" "C523"
			(at 0 0 90)
			(layer "B.SilkS")
			(hide yes)
			(effects
				(font
					(size 1.27 1.27)
				)
				(justify mirror)
			)
		)
		(property "Value" ""
			(at 0 0 90)
			(layer "B.Fab")
			(effects
				(font
					(size 1.27 1.27)
				)
				(justify mirror)
			)
		)
		(duplicate_pad_numbers_are_jumpers no)
		(fp_line
			(start -1.524 0.762)
			(end 1.524 0.762)
			(stroke
				(width 0.1524)
				(type default)
			)
			(layer "B.SilkS")
		)
		(fp_line
			(start 1.524 0.762)
			(end 1.524 -0.762)
			(stroke
				(width 0.1524)
				(type default)
			)
			(layer "B.SilkS")
		)
		(fp_line
			(start -1.524 -0.762)
			(end -1.524 0.762)
			(stroke
				(width 0.1524)
				(type default)
			)
			(layer "B.SilkS")
		)
		(fp_line
			(start 1.524 -0.762)
			(end -1.524 -0.762)
			(stroke
				(width 0.1524)
				(type default)
			)
			(layer "B.SilkS")
		)
		(fp_line
			(start -1.1049 0.724916)
			(end -1.1049 -0.724916)
			(stroke
				(width 0.1)
				(type default)
			)
			(layer "B.Fab")
		)
		(fp_line
			(start 1.1049 0.724916)
			(end -1.1049 0.724916)
			(stroke
				(width 0.1)
				(type default)
			)
			(layer "B.Fab")
		)
		(fp_line
			(start -1.1049 -0.724916)
			(end 1.1049 -0.724916)
			(stroke
				(width 0.1)
				(type default)
			)
			(layer "B.Fab")
		)
		(fp_line
			(start 1.1049 -0.724916)
			(end 1.1049 0.724916)
			(stroke
				(width 0.1)
				(type default)
			)
			(layer "B.Fab")
		)
		(pad "1" smd rect
			(at 0.889 0 270)
			(size 1.016 1.27)
			(layers "B.Cu" "B.Mask" "B.Paste")
			(net "PVCCFA_EHV_FIVRA_CPU0")
		)
		(pad "2" smd rect
			(at -0.889 0 270)
			(size 1.016 1.27)
			(layers "B.Cu" "B.Mask" "B.Paste")
			(net "GND")
		)
	)
)
